# T6G (Grand Teton) — schematic netlist excerpt (pin names and nets, part order shuffled) for the footprints in the layout excerpt that follows; sources: Cadence DE-HDL packaged netlist, KiCad conversion of 04192023_DAF0TMB3IC0_F0TG_MB_C_brd_V02_OCP.brd

PR834  Q_RES  21.5K 1% CHIP  pkg 0402LF  page 190 : A = P3V3_AUX_ILIM ; B = GND
R792  Q_RES  4.7K 5% CHIP  pkg 0201LF  page 331 : A = JTAG_TEST_MODE_RT_CPU1_P1 ; B = GND
PC6803  Q_CAP  22UF 16V 20% X6S  pkg C0805  page 361 : A = SW_P12V_AUX_P1V8_RETIMER_CPU1_FLT ; B = GND

(kicad_pcb
	(version 20260206)
	(generator "pcbnew")
	(generator_version "10.0")
	(general
		(thickness 1.6)
		(legacy_teardrops no)
	)
	(paper "A4")
	(title_block
		(title "04192023_DAF0TMB3IC0_F0TG_MB_C_brd_V02_OCP.brd")
		(comment 1 "Grand Teton / footprints 2541-2543 of 8354")
	)
	(layers
		(0 "F.Cu" signal "TOP")
		(4 "In1.Cu" signal "GND")
		(6 "In2.Cu" signal "IN1")
		(8 "In3.Cu" signal "GND1")
		(10 "In4.Cu" signal "IN2")
		(12 "In5.Cu" signal "GND2")
		(14 "In6.Cu" signal "IN3")
		(16 "In7.Cu" signal "GND3")
		(18 "In8.Cu" signal "VCC")
		(20 "In9.Cu" signal "VCC1")
		(22 "In10.Cu" signal "GND4")
		(24 "In11.Cu" signal "IN4")
		(26 "In12.Cu" signal "GND5")
		(28 "In13.Cu" signal "IN5")
		(30 "In14.Cu" signal "GND6")
		(32 "In15.Cu" signal "IN6")
		(34 "In16.Cu" signal "GND7")
		(2 "B.Cu" signal "BOTTOM")
		(9 "F.Adhes" user "F.Adhesive")
		(11 "B.Adhes" user "B.Adhesive")
		(13 "F.Paste" user "Package Geometry/Pastemask Top")
		(15 "B.Paste" user "Package Geometry/Pastemask Bottom")
		(5 "F.SilkS" user "Ref Des/Silkscreen Top")
		(7 "B.SilkS" user "Ref Des/Silkscreen Bottom")
		(1 "F.Mask" user "Board Geometry/Soldermask Top")
		(3 "B.Mask" user "Board Geometry/Soldermask Bottom")
		(17 "Dwgs.User" user "User.Drawings")
		(19 "Cmts.User" user "User.Comments")
		(21 "Eco1.User" user "User.Eco1")
		(23 "Eco2.User" user "User.Eco2")
		(25 "Edge.Cuts" user "Board Geometry/Outline")
		(27 "Margin" user)
		(31 "F.CrtYd" user "Package Geometry/Place Bound Top")
		(29 "B.CrtYd" user "Package Geometry/Place Bound Bottom")
		(35 "F.Fab" user "Ref Des/Assembly Top")
		(33 "B.Fab" user "Ref Des/Assembly Bottom")
	)
	(footprint ""
		(layer "F.Cu")
		(at 79.114904 -395.221206 -90)
		(property "Reference" "R792"
			(at 0 0 270)
			(layer "F.SilkS")
			(hide yes)
			(effects
				(font
					(size 1.27 1.27)
				)
			)
		)
		(property "Value" ""
			(at 0 0 270)
			(layer "F.Fab")
			(effects
				(font
					(size 1.27 1.27)
				)
			)
		)
		(duplicate_pad_numbers_are_jumpers no)
		(fp_line
			(start -0.32512 0.175006)
			(end -0.32512 -0.175006)
			(stroke
				(width 0.1)
				(type default)
			)
			(layer "F.Fab")
		)
		(fp_line
			(start 0.32512 0.175006)
			(end -0.32512 0.175006)
			(stroke
				(width 0.1)
				(type default)
			)
			(layer "F.Fab")
		)
		(fp_line
			(start -0.32512 -0.175006)
			(end 0.32512 -0.175006)
			(stroke
				(width 0.1)
				(type default)
			)
			(layer "F.Fab")
		)
		(fp_line
			(start 0.32512 -0.175006)
			(end 0.32512 0.175006)
			(stroke
				(width 0.1)
				(type default)
			)
			(layer "F.Fab")
		)
		(pad "1" smd rect
			(at -0.2667 0 270)
			(size 0.3048 0.381)
			(layers "F.Cu" "F.Mask" "F.Paste")
			(net "JTAG_TEST_MODE_RT_CPU1_P1")
		)
		(pad "2" smd rect
			(at 0.2667 0 90)
			(size 0.3048 0.381)
			(layers "F.Cu" "F.Mask" "F.Paste")
			(net "GND")
		)
	)
	(footprint ""
		(layer "F.Cu")
		(at 459.158594 -46.264576 -90)
		(property "Reference" "PR834"
			(at 0 0 270)
			(layer "F.SilkS")
			(hide yes)
			(effects
				(font
					(size 1.27 1.27)
				)
			)
		)
		(property "Value" ""
			(at 0 0 270)
			(layer "F.Fab")
			(effects
				(font
					(size 1.27 1.27)
				)
			)
		)
		(duplicate_pad_numbers_are_jumpers no)
		(fp_line
			(start -0.7874 0.4064)
			(end -0.7874 -0.4064)
			(stroke
				(width 0.1524)
				(type default)
			)
			(layer "F.SilkS")
		)
		(fp_line
			(start 0.7874 0.4064)
			(end -0.7874 0.4064)
			(stroke
				(width 0.1524)
				(type default)
			)
			(layer "F.SilkS")
		)
		(fp_line
			(start -0.7874 -0.4064)
			(end 0.7874 -0.4064)
			(stroke
				(width 0.1524)
				(type default)
			)
			(layer "F.SilkS")
		)
		(fp_line
			(start 0.7874 -0.4064)
			(end 0.7874 0.4064)
			(stroke
				(width 0.1524)
				(type default)
			)
			(layer "F.SilkS")
		)
		(fp_line
			(start -0.67945 0.3048)
			(end -0.67945 -0.305054)
			(stroke
				(width 0.1)
				(type default)
			)
			(layer "F.Fab")
		)
		(fp_line
			(start -0.12065 0.3048)
			(end -0.67945 0.3048)
			(stroke
				(width 0.1)
				(type default)
			)
			(layer "F.Fab")
		)
		(fp_line
			(start 0.120396 0.3048)
			(end 0.120396 0.2794)
			(stroke
				(width 0.1)
				(type default)
			)
			(layer "F.Fab")
		)
		(fp_line
			(start 0.67945 0.3048)
			(end 0.120396 0.3048)
			(stroke
				(width 0.1)
				(type default)
			)
			(layer "F.Fab")
		)
		(fp_line
			(start -0.12065 0.2794)
			(end -0.12065 0.3048)
			(stroke
				(width 0.1)
				(type default)
			)
			(layer "F.Fab")
		)
		(fp_line
			(start 0.120396 0.2794)
			(end -0.12065 0.2794)
			(stroke
				(width 0.1)
				(type default)
			)
			(layer "F.Fab")
		)
		(fp_line
			(start -0.12065 -0.2794)
			(end 0.12065 -0.2794)
			(stroke
				(width 0.1)
				(type default)
			)
			(layer "F.Fab")
		)
		(fp_line
			(start 0.12065 -0.2794)
			(end 0.12065 -0.3048)
			(stroke
				(width 0.1)
				(type default)
			)
			(layer "F.Fab")
		)
		(fp_line
			(start 0.12065 -0.3048)
			(end 0.67945 -0.3048)
			(stroke
				(width 0.1)
				(type default)
			)
			(layer "F.Fab")
		)
		(fp_line
			(start 0.67945 -0.3048)
			(end 0.67945 0.3048)
			(stroke
				(width 0.1)
				(type default)
			)
			(layer "F.Fab")
		)
		(fp_line
			(start -0.67945 -0.305054)
			(end -0.12065 -0.305054)
			(stroke
				(width 0.1)
				(type default)
			)
			(layer "F.Fab")
		)
		(fp_line
			(start -0.12065 -0.305054)
			(end -0.12065 -0.2794)
			(stroke
				(width 0.1)
				(type default)
			)
			(layer "F.Fab")
		)
		(pad "1" smd circle
			(at -0.40005 0 270)
			(size 0 0)
			(layers "F.Cu" "F.Mask" "F.Paste")
			(net "P3V3_AUX_ILIM")
		)
		(pad "2" smd circle
			(at 0.40005 0 270)
			(size 0 0)
			(layers "F.Cu" "F.Mask" "F.Paste")
			(net "GND")
		)
	)
	(footprint ""
		(layer "F.Cu")
		(at 233.2228 -281.7368)
		(property "Reference" "PC6803"
			(at 0 0 0)
			(layer "F.SilkS")
			(hide yes)
			(effects
				(font
					(size 1.27 1.27)
				)
			)
		)
		(property "Value" ""
			(at 0 0 0)
			(layer "F.Fab")
			(effects
				(font
					(size 1.27 1.27)
				)
			)
		)
		(duplicate_pad_numbers_are_jumpers no)
		(fp_line
			(start -1.524 -0.762)
			(end 1.524 -0.762)
			(stroke
				(width 0.1524)
				(type default)
			)
			(layer "F.SilkS")
		)
		(fp_line
			(start -1.524 0.762)
			(end -1.524 -0.762)
			(stroke
				(width 0.1524)
				(type default)
			)
			(layer "F.SilkS")
		)
		(fp_line
			(start 1.524 -0.762)
			(end 1.524 0.762)
			(stroke
				(width 0.1524)
				(type default)
			)
			(layer "F.SilkS")
		)
		(fp_line
			(start 1.524 0.762)
			(end -1.524 0.762)
			(stroke
				(width 0.1524)
				(type default)
			)
			(layer "F.SilkS")
		)
		(fp_line
			(start -1.1049 -0.724916)
			(end -1.1049 0.724916)
			(stroke
				(width 0.1)
				(type default)
			)
			(layer "F.Fab")
		)
		(fp_line
			(start -1.1049 0.724916)
			(end 1.1049 0.724916)
			(stroke
				(width 0.1)
				(type default)
			)
			(layer "F.Fab")
		)
		(fp_line
			(start 1.1049 -0.724916)
			(end -1.1049 -0.724916)
			(stroke
				(width 0.1)
				(type default)
			)
			(layer "F.Fab")
		)
		(fp_line
			(start 1.1049 0.724916)
			(end 1.1049 -0.724916)
			(stroke
				(width 0.1)
				(type default)
			)
			(layer "F.Fab")
		)
		(pad "1" smd rect
			(at -0.889 0 180)
			(size 1.016 1.27)
			(layers "F.Cu" "F.Mask" "F.Paste")
			(net "SW_P12V_AUX_P1V8_RETIMER_CPU1_FLT")
		)
		(pad "2" smd rect
			(at 0.889 0 180)
			(size 1.016 1.27)
			(layers "F.Cu" "F.Mask" "F.Paste")
			(net "GND")
		)
	)
)
